(kicad_pcb
	(version 20260206)
	(generator "pcbnew")
	(generator_version "10.0")
	(general
		(thickness 1.21888)
		(legacy_teardrops no)
	)
	(paper "A4")
	(title_block
		(title "timecard-proto-v0 — Timingcard_PCB.PcbDoc")
		(comment 1 "Time Appliance Project (Time Card) / footprints 27-30 of 167")
	)
	(layers
		(0 "F.Cu" signal "TOP")
		(4 "In1.Cu" signal "SGND")
		(6 "In2.Cu" signal "IN1")
		(8 "In3.Cu" signal "IN2")
		(10 "In4.Cu" signal "SGND1")
		(2 "B.Cu" signal "BOTTOM")
		(9 "F.Adhes" user "F.Adhesive")
		(11 "B.Adhes" user "B.Adhesive")
		(13 "F.Paste" user "Top Paste")
		(15 "B.Paste" user "Bottom Paste")
		(5 "F.SilkS" user "Top Overlay")
		(7 "B.SilkS" user "Bottom Overlay")
		(1 "F.Mask" user "Top Solder")
		(3 "B.Mask" user "Bottom Solder")
		(17 "Dwgs.User" user "User.Drawings")
		(19 "Cmts.User" user "User.Comments")
		(21 "Eco1.User" user "User.Eco1")
		(23 "Eco2.User" user "User.Eco2")
		(25 "Edge.Cuts" user)
		(27 "Margin" user)
		(31 "F.CrtYd" user "Top Courtyard")
		(29 "B.CrtYd" user "Bottom Courtyard")
		(35 "F.Fab" user "Top Component Center")
		(33 "B.Fab" user "Bottom Component Center")
	)
	(footprint "Vault:FP-5TS1-IPC_C"
		(layer "F.Cu")
		(at 170.588595 63.5786 90)
		(property "Reference" "U7"
			(at -0.698915 -3.135129 90)
			(unlocked yes)
			(layer "F.SilkS")
			(effects
				(font
					(size 0.762 0.762)
					(thickness 0.2286)
				)
			)
		)
		(property "Value" "AT24MAC402-STUM-T"
			(at 10.752795 3.216402 90)
			(unlocked yes)
			(layer "F.SilkS")
			(hide yes)
			(effects
				(font
					(size 1.524 1.524)
					(thickness 0.254)
				)
			)
		)
		(sheetname "GPS_IMU_SENSORS")
		(sheetfile "GPS_IMU_SENSORS.kicad_sch")
		(duplicate_pad_numbers_are_jumpers no)
		(fp_line
			(start -0.17207 -1.45)
			(end 0.17207 -1.45)
			(stroke
				(width 0.2)
				(type solid)
			)
			(layer "F.SilkS")
		)
		(fp_line
			(start 0.8 -0.30893)
			(end 0.8 0.30894)
			(stroke
				(width 0.2)
				(type solid)
			)
			(layer "F.SilkS")
		)
		(fp_line
			(start -0.17207 1.45)
			(end 0.17207 1.45)
			(stroke
				(width 0.2)
				(type solid)
			)
			(layer "F.SilkS")
		)
		(fp_circle
			(center -2.21035 -0.95)
			(end -2.08535 -0.95)
			(stroke
				(width 0.25)
				(type solid)
			)
			(fill no)
			(layer "F.SilkS")
		)
		(fp_line
			(start 1.68536 -1.55)
			(end 1.68536 1.55)
			(stroke
				(width 0.2)
				(type solid)
			)
			(layer "F.CrtYd")
		)
		(fp_line
			(start -1.68536 -1.55)
			(end 1.68536 -1.55)
			(stroke
				(width 0.2)
				(type solid)
			)
			(layer "F.CrtYd")
		)
		(fp_line
			(start -1.68536 -1.55)
			(end -1.68536 1.55)
			(stroke
				(width 0.2)
				(type solid)
			)
			(layer "F.CrtYd")
		)
		(fp_line
			(start -1.68536 1.55)
			(end 1.68536 1.55)
			(stroke
				(width 0.2)
				(type solid)
			)
			(layer "F.CrtYd")
		)
		(fp_line
			(start 1.68536 -1.55)
			(end 1.68536 1.55)
			(stroke
				(width 0.2)
				(type solid)
			)
			(layer "F.Fab")
		)
		(fp_line
			(start -1.68536 -1.55)
			(end 1.68536 -1.55)
			(stroke
				(width 0.2)
				(type solid)
			)
			(layer "F.Fab")
		)
		(fp_line
			(start -1.68536 -1.55)
			(end -1.68536 1.55)
			(stroke
				(width 0.2)
				(type solid)
			)
			(layer "F.Fab")
		)
		(fp_line
			(start 0 -0.5)
			(end 0 0.5)
			(stroke
				(width 0.1)
				(type solid)
			)
			(layer "F.Fab")
		)
		(fp_line
			(start -0.5 0)
			(end 0.5 0)
			(stroke
				(width 0.1)
				(type solid)
			)
			(layer "F.Fab")
		)
		(fp_line
			(start -1.68536 1.55)
			(end 1.68536 1.55)
			(stroke
				(width 0.2)
				(type solid)
			)
			(layer "F.Fab")
		)
		(fp_text user "${REFERENCE}"
			(at 0 0.28494 90)
			(unlocked yes)
			(layer "F.Fab")
			(effects
				(font
					(face "Arial")
					(size 0.63 0.63)
					(thickness 0.1)
				)
				(justify left bottom)
			)
		)
		(pad "1" smd rect
			(at -1.06621 -0.95 90)
			(size 1.03828 0.53213)
			(layers "F.Cu" "F.Mask" "F.Paste")
			(net "SCL")
			(solder_mask_margin 0)
			(solder_paste_margin 0)
		)
		(pad "2" smd roundrect
			(at -1.06621 0 90)
			(size 1.03828 0.53213)
			(layers "F.Cu" "F.Mask" "F.Paste")
			(roundrect_rratio 0.5)
			(net "GND")
			(solder_mask_margin 0)
			(solder_paste_margin 0)
		)
		(pad "3" smd roundrect
			(at -1.06621 0.95 90)
			(size 1.03828 0.53213)
			(layers "F.Cu" "F.Mask" "F.Paste")
			(roundrect_rratio 0.5)
			(net "SDA")
			(solder_mask_margin 0)
			(solder_paste_margin 0)
		)
		(pad "4" smd roundrect
			(at 1.06621 0.95 90)
			(size 1.03828 0.53213)
			(layers "F.Cu" "F.Mask" "F.Paste")
			(roundrect_rratio 0.5)
			(net "+3.3V")
			(solder_mask_margin 0)
			(solder_paste_margin 0)
		)
		(pad "5" smd roundrect
			(at 1.06621 -0.95 90)
			(size 1.03828 0.53213)
			(layers "F.Cu" "F.Mask" "F.Paste")
			(roundrect_rratio 0.5)
			(net "EXT_EEPROM_WP")
			(solder_mask_margin 0)
			(solder_paste_margin 0)
		)
	)
	(footprint "Resistors:RESC1005X04N"
		(layer "F.Cu")
		(at 122.088595 145.5786 -90)
		(property "Reference" "R23"
			(at 1.27491 0.808535 90)
			(unlocked yes)
			(layer "F.SilkS")
			(effects
				(font
					(size 0.762 0.762)
					(thickness 0.2286)
				)
				(justify left bottom)
			)
		)
		(property "Value" "ERJ-2GE0R00X"
			(at 3.42519 0.2413 0)
			(unlocked yes)
			(layer "F.SilkS")
			(hide yes)
			(effects
				(font
					(size 1.524 1.524)
					(thickness 0.254)
				)
				(justify left bottom)
			)
		)
		(sheetname "PCIe_JTAG")
		(sheetfile "PCIe_JTAG.kicad_sch")
		(duplicate_pad_numbers_are_jumpers no)
		(pad "1" smd rect
			(at -0.425 0)
			(size 0.6 0.65)
			(layers "F.Cu" "F.Mask" "F.Paste")
			(net "PRSNT")
		)
		(pad "2" smd rect
			(at 0.425 0)
			(size 0.6 0.65)
			(layers "F.Cu" "F.Mask" "F.Paste")
			(net "NetP2_B17")
		)
	)
	(footprint "Passives:SOT65P210X110-3N"
		(layer "F.Cu")
		(at 130.493595 66.4446 -90)
		(property "Reference" "D5"
			(at 4.00019 -1.629865 90)
			(unlocked yes)
			(layer "F.SilkS")
			(effects
				(font
					(size 0.762 0.762)
					(thickness 0.2286)
				)
				(justify left bottom)
			)
		)
		(property "Value" "BAT54SW"
			(at 3.88239 1.5875 0)
			(unlocked yes)
			(layer "F.SilkS")
			(hide yes)
			(effects
				(font
					(size 1.524 1.524)
					(thickness 0.254)
				)
				(justify left bottom)
			)
		)
		(sheetname "PCIe_JTAG")
		(sheetfile "PCIe_JTAG.kicad_sch")
		(duplicate_pad_numbers_are_jumpers no)
		(fp_line
			(start 0.675 1.1)
			(end -0.325 1.1)
			(stroke
				(width 0.2)
				(type solid)
			)
			(layer "F.SilkS")
		)
		(fp_line
			(start 0.675 1.1)
			(end 0.675 0.65)
			(stroke
				(width 0.2)
				(type solid)
			)
			(layer "F.SilkS")
		)
		(fp_line
			(start 0.675 -0.65)
			(end 0.675 -1.1)
			(stroke
				(width 0.2)
				(type solid)
			)
			(layer "F.SilkS")
		)
		(fp_line
			(start 0.675 -1.1)
			(end -0.325 -1.1)
			(stroke
				(width 0.2)
				(type solid)
			)
			(layer "F.SilkS")
		)
		(fp_circle
			(center -1.125 -1.45)
			(end -1.25 -1.45)
			(stroke
				(width 0.25)
				(type solid)
			)
			(fill no)
			(layer "F.SilkS")
		)
		(pad "1" smd rect
			(at -1.125 -0.65)
			(size 0.5 0.9)
			(layers "F.Cu" "F.Mask" "F.Paste")
			(net "GND")
		)
		(pad "2" smd rect
			(at -1.125 0.65)
			(size 0.5 0.9)
			(layers "F.Cu" "F.Mask" "F.Paste")
			(net "+3.3V")
		)
		(pad "3" smd rect
			(at 1.125 0)
			(size 0.5 0.9)
			(layers "F.Cu" "F.Mask" "F.Paste")
			(net "FPGA_TCK")
		)
	)
	(footprint "Passives:DIOM1608X06N"
		(layer "F.Cu")
		(at 74.867595 53.2366 90)
		(property "Reference" "D11"
			(at -1.21245 -1.265735 90)
			(unlocked yes)
			(layer "F.SilkS")
			(effects
				(font
					(size 0.762 0.762)
					(thickness 0.2286)
				)
				(justify left bottom)
			)
		)
		(property "Value" "RED"
			(at -3.22199 -1.4097 0)
			(unlocked yes)
			(layer "F.SilkS")
			(hide yes)
			(effects
				(font
					(size 1.524 1.524)
					(thickness 0.254)
				)
				(justify left bottom)
			)
		)
		(sheetname "USER_IO")
		(sheetfile "USER_IO.kicad_sch")
		(duplicate_pad_numbers_are_jumpers no)
		(fp_circle
			(center -1.275 -0.725)
			(end -1.225 -0.725)
			(stroke
				(width 0.1)
				(type solid)
			)
			(fill no)
			(layer "F.SilkS")
		)
		(pad "1" smd rect
			(at -0.725 0 180)
			(size 0.85 1)
			(layers "F.Cu" "F.Mask" "F.Paste")
			(net "NetD11_1")
		)
		(pad "2" smd rect
			(at 0.725 0 180)
			(size 0.85 1)
			(layers "F.Cu" "F.Mask" "F.Paste")
			(net "+3.3V")
		)
	)
)
